(kicad_pcb
	(version 20260206)
	(generator "pcbnew")
	(generator_version "10.0")
	(general
		(thickness 1.6)
		(legacy_teardrops no)
	)
	(paper "A4")
	(title_block
		(title "03242023_DA0F0TMBIJ0_F0T_Motherboard_J_brd_V01_OCP.brd")
		(comment 1 "Grand Teton / footprints 4472-4477 of 6105")
	)
	(layers
		(0 "F.Cu" signal "TOP")
		(4 "In1.Cu" signal "GND")
		(6 "In2.Cu" signal "IN1")
		(8 "In3.Cu" signal "GND1")
		(10 "In4.Cu" signal "IN2")
		(12 "In5.Cu" signal "GND2")
		(14 "In6.Cu" signal "IN3")
		(16 "In7.Cu" signal "GND3")
		(18 "In8.Cu" signal "VCC")
		(20 "In9.Cu" signal "VCC1")
		(22 "In10.Cu" signal "GND4")
		(24 "In11.Cu" signal "IN4")
		(26 "In12.Cu" signal "GND5")
		(28 "In13.Cu" signal "IN5")
		(30 "In14.Cu" signal "GND6")
		(32 "In15.Cu" signal "IN6")
		(34 "In16.Cu" signal "GND7")
		(2 "B.Cu" signal "BOTTOM")
		(9 "F.Adhes" user "F.Adhesive")
		(11 "B.Adhes" user "B.Adhesive")
		(13 "F.Paste" user "Package Geometry/Pastemask Top")
		(15 "B.Paste" user "Package Geometry/Pastemask Bottom")
		(5 "F.SilkS" user "Ref Des/Silkscreen Top")
		(7 "B.SilkS" user "Ref Des/Silkscreen Bottom")
		(1 "F.Mask" user "Board Geometry/Soldermask Top")
		(3 "B.Mask" user "Board Geometry/Soldermask Bottom")
		(17 "Dwgs.User" user "User.Drawings")
		(19 "Cmts.User" user "User.Comments")
		(21 "Eco1.User" user "User.Eco1")
		(23 "Eco2.User" user "User.Eco2")
		(25 "Edge.Cuts" user "Board Geometry/Outline")
		(27 "Margin" user)
		(31 "F.CrtYd" user "Package Geometry/Place Bound Top")
		(29 "B.CrtYd" user "Package Geometry/Place Bound Bottom")
		(35 "F.Fab" user "Ref Des/Assembly Top")
		(33 "B.Fab" user "Ref Des/Assembly Bottom")
	)
	(footprint ""
		(layer "B.Cu")
		(at 337.622134 -136.479534 180)
		(property "Reference" "R1021"
			(at 0 0 0)
			(layer "B.SilkS")
			(hide yes)
			(effects
				(font
					(size 1.27 1.27)
				)
				(justify mirror)
			)
		)
		(property "Value" ""
			(at 0 0 0)
			(layer "B.Fab")
			(effects
				(font
					(size 1.27 1.27)
				)
				(justify mirror)
			)
		)
		(duplicate_pad_numbers_are_jumpers no)
		(fp_line
			(start 0.7874 -0.083566)
			(end 0.7874 -0.4064)
			(stroke
				(width 0.1524)
				(type default)
			)
			(layer "B.SilkS")
		)
		(fp_line
			(start 0.7874 -0.4064)
			(end -0.7874 -0.4064)
			(stroke
				(width 0.1524)
				(type default)
			)
			(layer "B.SilkS")
		)
		(fp_line
			(start -0.169926 0.4064)
			(end 0.495554 0.4064)
			(stroke
				(width 0.1524)
				(type default)
			)
			(layer "B.SilkS")
		)
		(fp_line
			(start -0.7874 0.4064)
			(end -0.604266 0.4064)
			(stroke
				(width 0.1524)
				(type default)
			)
			(layer "B.SilkS")
		)
		(fp_line
			(start -0.7874 -0.4064)
			(end -0.7874 0.4064)
			(stroke
				(width 0.1524)
				(type default)
			)
			(layer "B.SilkS")
		)
		(fp_line
			(start 0.67945 0.3048)
			(end 0.67945 -0.305054)
			(stroke
				(width 0.1)
				(type default)
			)
			(layer "B.Fab")
		)
		(fp_line
			(start 0.67945 -0.305054)
			(end 0.12065 -0.305054)
			(stroke
				(width 0.1)
				(type default)
			)
			(layer "B.Fab")
		)
		(fp_line
			(start 0.12065 0.3048)
			(end 0.67945 0.3048)
			(stroke
				(width 0.1)
				(type default)
			)
			(layer "B.Fab")
		)
		(fp_line
			(start 0.12065 0.2794)
			(end 0.12065 0.3048)
			(stroke
				(width 0.1)
				(type default)
			)
			(layer "B.Fab")
		)
		(fp_line
			(start 0.12065 -0.2794)
			(end -0.12065 -0.2794)
			(stroke
				(width 0.1)
				(type default)
			)
			(layer "B.Fab")
		)
		(fp_line
			(start 0.12065 -0.305054)
			(end 0.12065 -0.2794)
			(stroke
				(width 0.1)
				(type default)
			)
			(layer "B.Fab")
		)
		(fp_line
			(start -0.120396 0.3048)
			(end -0.120396 0.2794)
			(stroke
				(width 0.1)
				(type default)
			)
			(layer "B.Fab")
		)
		(fp_line
			(start -0.120396 0.2794)
			(end 0.12065 0.2794)
			(stroke
				(width 0.1)
				(type default)
			)
			(layer "B.Fab")
		)
		(fp_line
			(start -0.12065 -0.2794)
			(end -0.12065 -0.3048)
			(stroke
				(width 0.1)
				(type default)
			)
			(layer "B.Fab")
		)
		(fp_line
			(start -0.12065 -0.3048)
			(end -0.67945 -0.3048)
			(stroke
				(width 0.1)
				(type default)
			)
			(layer "B.Fab")
		)
		(fp_line
			(start -0.67945 0.3048)
			(end -0.120396 0.3048)
			(stroke
				(width 0.1)
				(type default)
			)
			(layer "B.Fab")
		)
		(fp_line
			(start -0.67945 -0.3048)
			(end -0.67945 0.3048)
			(stroke
				(width 0.1)
				(type default)
			)
			(layer "B.Fab")
		)
		(pad "1" smd rect
			(at 0.40005 0 180)
			(size 0.4572 0.508)
			(layers "B.Cu" "B.Mask" "B.Paste")
			(net "CLK_25M_CK440_CPU0_R_DN")
		)
		(pad "2" smd rect
			(at -0.40005 0 180)
			(size 0.4572 0.508)
			(layers "B.Cu" "B.Mask" "B.Paste")
			(net "CLK_25M_NSSC_CPU0_DN")
		)
	)
	(footprint ""
		(layer "B.Cu")
		(at 308.901846 -316.14999 -90)
		(property "Reference" "D42"
			(at 1.284732 1.231646 0)
			(unlocked yes)
			(layer "B.SilkS")
			(effects
				(font
					(size 0.7874 0.5842)
					(thickness 0.1524)
				)
				(justify left mirror)
			)
		)
		(property "Value" ""
			(at 0 0 90)
			(layer "B.Fab")
			(effects
				(font
					(size 1.27 1.27)
				)
				(justify mirror)
			)
		)
		(duplicate_pad_numbers_are_jumpers no)
		(fp_line
			(start -2.050796 0.700024)
			(end 2.050796 0.700024)
			(stroke
				(width 0.1524)
				(type default)
			)
			(layer "B.SilkS")
		)
		(fp_line
			(start 2.050796 0.700024)
			(end 2.050796 -0.700024)
			(stroke
				(width 0.1524)
				(type default)
			)
			(layer "B.SilkS")
		)
		(fp_line
			(start -2.343404 0.6985)
			(end -2.216404 0.6985)
			(stroke
				(width 0.1524)
				(type default)
			)
			(layer "B.SilkS")
		)
		(fp_line
			(start -2.229104 0.6985)
			(end -2.051304 0.6985)
			(stroke
				(width 0.1524)
				(type default)
			)
			(layer "B.SilkS")
		)
		(fp_line
			(start -2.051304 0.6985)
			(end -2.051304 0.635)
			(stroke
				(width 0.1524)
				(type default)
			)
			(layer "B.SilkS")
		)
		(fp_line
			(start -2.152904 0.635)
			(end -2.152904 -0.6985)
			(stroke
				(width 0.1524)
				(type default)
			)
			(layer "B.SilkS")
		)
		(fp_line
			(start -2.051304 0.635)
			(end -2.152904 0.635)
			(stroke
				(width 0.1524)
				(type default)
			)
			(layer "B.SilkS")
		)
		(fp_line
			(start 0.30607 0.500126)
			(end -0.193802 0)
			(stroke
				(width 0.1524)
				(type default)
			)
			(layer "B.SilkS")
		)
		(fp_line
			(start -0.193802 0)
			(end 0.30607 -0.500126)
			(stroke
				(width 0.1524)
				(type default)
			)
			(layer "B.SilkS")
		)
		(fp_line
			(start -0.293878 -0.500126)
			(end -0.293878 0.500126)
			(stroke
				(width 0.1524)
				(type default)
			)
			(layer "B.SilkS")
		)
		(fp_line
			(start 0.30607 -0.500126)
			(end 0.30607 0.500126)
			(stroke
				(width 0.1524)
				(type default)
			)
			(layer "B.SilkS")
		)
		(fp_line
			(start -2.064004 -0.6731)
			(end -2.064004 -0.6985)
			(stroke
				(width 0.1524)
				(type default)
			)
			(layer "B.SilkS")
		)
		(fp_line
			(start -2.343404 -0.6985)
			(end -2.343404 0.6985)
			(stroke
				(width 0.1524)
				(type default)
			)
			(layer "B.SilkS")
		)
		(fp_line
			(start -2.229104 -0.6985)
			(end -2.229104 0.6985)
			(stroke
				(width 0.1524)
				(type default)
			)
			(layer "B.SilkS")
		)
		(fp_line
			(start -2.152904 -0.6985)
			(end -2.343404 -0.6985)
			(stroke
				(width 0.1524)
				(type default)
			)
			(layer "B.SilkS")
		)
		(fp_line
			(start -2.064004 -0.6985)
			(end -2.229104 -0.6985)
			(stroke
				(width 0.1524)
				(type default)
			)
			(layer "B.SilkS")
		)
		(fp_line
			(start -2.050796 -0.700024)
			(end -2.050796 0.700024)
			(stroke
				(width 0.1524)
				(type default)
			)
			(layer "B.SilkS")
		)
		(fp_line
			(start 2.050796 -0.700024)
			(end -2.050796 -0.700024)
			(stroke
				(width 0.1524)
				(type default)
			)
			(layer "B.SilkS")
		)
		(fp_line
			(start -0.899922 0.700024)
			(end 0.899922 0.700024)
			(stroke
				(width 0.1)
				(type default)
			)
			(layer "B.Fab")
		)
		(fp_line
			(start 0.899922 0.700024)
			(end 0.899922 -0.700024)
			(stroke
				(width 0.1)
				(type default)
			)
			(layer "B.Fab")
		)
		(fp_line
			(start -0.899922 -0.700024)
			(end -0.899922 0.700024)
			(stroke
				(width 0.1)
				(type default)
			)
			(layer "B.Fab")
		)
		(fp_line
			(start 0.899922 -0.700024)
			(end -0.899922 -0.700024)
			(stroke
				(width 0.1)
				(type default)
			)
			(layer "B.Fab")
		)
		(fp_text user "-"
			(at -3.65633 0.895096 90)
			(unlocked yes)
			(layer "B.SilkS")
			(effects
				(font
					(size 1.905 1.4224)
					(thickness 0.1524)
				)
				(justify left mirror)
			)
		)
		(fp_text user "+"
			(at 3.123946 0.762 180)
			(unlocked yes)
			(layer "B.SilkS")
			(effects
				(font
					(size 1.905 1.4224)
					(thickness 0.1524)
				)
				(justify left mirror)
			)
		)
		(fp_text user "+"
			(at 3.123946 0.762 180)
			(unlocked yes)
			(layer "B.Fab")
			(effects
				(font
					(size 1.905 1.4224)
					(thickness 0.1524)
				)
				(justify left mirror)
			)
		)
		(fp_text user "-"
			(at -3.880104 0.23495 90)
			(unlocked yes)
			(layer "B.Fab")
			(effects
				(font
					(size 1.905 1.4224)
					(thickness 0.1524)
				)
				(justify left mirror)
			)
		)
		(pad "1" smd rect
			(at 1.199896 0 180)
			(size 0.6604 1.3716)
			(layers "B.Cu" "B.Mask" "B.Paste")
			(net "PWRGD_FAIL_CPU0_AB_R1")
		)
		(pad "2" smd rect
			(at -1.199896 0)
			(size 0.6604 1.3716)
			(layers "B.Cu" "B.Mask" "B.Paste")
			(net "P3V3_AUX")
		)
	)
	(footprint ""
		(layer "B.Cu")
		(at 213.79688 -54.447948 90)
		(property "Reference" "R3751"
			(at 0 0 90)
			(layer "B.SilkS")
			(hide yes)
			(effects
				(font
					(size 1.27 1.27)
				)
				(justify mirror)
			)
		)
		(property "Value" ""
			(at 0 0 90)
			(layer "B.Fab")
			(effects
				(font
					(size 1.27 1.27)
				)
				(justify mirror)
			)
		)
		(duplicate_pad_numbers_are_jumpers no)
		(fp_line
			(start 0.7874 -0.4064)
			(end -0.7874 -0.4064)
			(stroke
				(width 0.1524)
				(type default)
			)
			(layer "B.SilkS")
		)
		(fp_line
			(start -0.7874 -0.4064)
			(end -0.7874 0.4064)
			(stroke
				(width 0.1524)
				(type default)
			)
			(layer "B.SilkS")
		)
		(fp_line
			(start 0.7874 0.4064)
			(end 0.7874 -0.4064)
			(stroke
				(width 0.1524)
				(type default)
			)
			(layer "B.SilkS")
		)
		(fp_line
			(start -0.7874 0.4064)
			(end 0.7874 0.4064)
			(stroke
				(width 0.1524)
				(type default)
			)
			(layer "B.SilkS")
		)
		(fp_line
			(start 0.67945 -0.305054)
			(end 0.12065 -0.305054)
			(stroke
				(width 0.1)
				(type default)
			)
			(layer "B.Fab")
		)
		(fp_line
			(start 0.12065 -0.305054)
			(end 0.12065 -0.2794)
			(stroke
				(width 0.1)
				(type default)
			)
			(layer "B.Fab")
		)
		(fp_line
			(start -0.12065 -0.3048)
			(end -0.67945 -0.3048)
			(stroke
				(width 0.1)
				(type default)
			)
			(layer "B.Fab")
		)
		(fp_line
			(start -0.67945 -0.3048)
			(end -0.67945 0.3048)
			(stroke
				(width 0.1)
				(type default)
			)
			(layer "B.Fab")
		)
		(fp_line
			(start 0.12065 -0.2794)
			(end -0.12065 -0.2794)
			(stroke
				(width 0.1)
				(type default)
			)
			(layer "B.Fab")
		)
		(fp_line
			(start -0.12065 -0.2794)
			(end -0.12065 -0.3048)
			(stroke
				(width 0.1)
				(type default)
			)
			(layer "B.Fab")
		)
		(fp_line
			(start 0.12065 0.2794)
			(end 0.12065 0.3048)
			(stroke
				(width 0.1)
				(type default)
			)
			(layer "B.Fab")
		)
		(fp_line
			(start -0.120396 0.2794)
			(end 0.12065 0.2794)
			(stroke
				(width 0.1)
				(type default)
			)
			(layer "B.Fab")
		)
		(fp_line
			(start 0.67945 0.3048)
			(end 0.67945 -0.305054)
			(stroke
				(width 0.1)
				(type default)
			)
			(layer "B.Fab")
		)
		(fp_line
			(start 0.12065 0.3048)
			(end 0.67945 0.3048)
			(stroke
				(width 0.1)
				(type default)
			)
			(layer "B.Fab")
		)
		(fp_line
			(start -0.120396 0.3048)
			(end -0.120396 0.2794)
			(stroke
				(width 0.1)
				(type default)
			)
			(layer "B.Fab")
		)
		(fp_line
			(start -0.67945 0.3048)
			(end -0.120396 0.3048)
			(stroke
				(width 0.1)
				(type default)
			)
			(layer "B.Fab")
		)
		(pad "1" smd circle
			(at 0.40005 0 270)
			(size 0 0)
			(layers "B.Cu" "B.Mask" "B.Paste")
			(net "INA230_2_A0")
		)
		(pad "2" smd circle
			(at -0.40005 0 270)
			(size 0 0)
			(layers "B.Cu" "B.Mask" "B.Paste")
			(net "SMB_INA230_2_3V3AUX_SDA_R1")
		)
	)
	(footprint ""
		(layer "B.Cu")
		(at 156.720032 -39.8653 90)
		(property "Reference" "C2318"
			(at 0 0 90)
			(layer "B.SilkS")
			(hide yes)
			(effects
				(font
					(size 1.27 1.27)
				)
				(justify mirror)
			)
		)
		(property "Value" ""
			(at 0 0 90)
			(layer "B.Fab")
			(effects
				(font
					(size 1.27 1.27)
				)
				(justify mirror)
			)
		)
		(duplicate_pad_numbers_are_jumpers no)
		(fp_line
			(start 0.7874 -0.4064)
			(end -0.7874 -0.4064)
			(stroke
				(width 0.1524)
				(type default)
			)
			(layer "B.SilkS")
		)
		(fp_line
			(start -0.7874 -0.4064)
			(end -0.7874 0.4064)
			(stroke
				(width 0.1524)
				(type default)
			)
			(layer "B.SilkS")
		)
		(fp_line
			(start 0.7874 0.4064)
			(end 0.7874 -0.4064)
			(stroke
				(width 0.1524)
				(type default)
			)
			(layer "B.SilkS")
		)
		(fp_line
			(start -0.7874 0.4064)
			(end 0.7874 0.4064)
			(stroke
				(width 0.1524)
				(type default)
			)
			(layer "B.SilkS")
		)
		(fp_line
			(start 0.67945 -0.305054)
			(end 0.12065 -0.305054)
			(stroke
				(width 0.1)
				(type default)
			)
			(layer "B.Fab")
		)
		(fp_line
			(start 0.12065 -0.305054)
			(end 0.12065 -0.2794)
			(stroke
				(width 0.1)
				(type default)
			)
			(layer "B.Fab")
		)
		(fp_line
			(start -0.12065 -0.3048)
			(end -0.67945 -0.3048)
			(stroke
				(width 0.1)
				(type default)
			)
			(layer "B.Fab")
		)
		(fp_line
			(start -0.67945 -0.3048)
			(end -0.67945 0.3048)
			(stroke
				(width 0.1)
				(type default)
			)
			(layer "B.Fab")
		)
		(fp_line
			(start 0.12065 -0.2794)
			(end -0.12065 -0.2794)
			(stroke
				(width 0.1)
				(type default)
			)
			(layer "B.Fab")
		)
		(fp_line
			(start -0.12065 -0.2794)
			(end -0.12065 -0.3048)
			(stroke
				(width 0.1)
				(type default)
			)
			(layer "B.Fab")
		)
		(fp_line
			(start 0.12065 0.2794)
			(end 0.12065 0.3048)
			(stroke
				(width 0.1)
				(type default)
			)
			(layer "B.Fab")
		)
		(fp_line
			(start -0.120396 0.2794)
			(end 0.12065 0.2794)
			(stroke
				(width 0.1)
				(type default)
			)
			(layer "B.Fab")
		)
		(fp_line
			(start 0.67945 0.3048)
			(end 0.67945 -0.305054)
			(stroke
				(width 0.1)
				(type default)
			)
			(layer "B.Fab")
		)
		(fp_line
			(start 0.12065 0.3048)
			(end 0.67945 0.3048)
			(stroke
				(width 0.1)
				(type default)
			)
			(layer "B.Fab")
		)
		(fp_line
			(start -0.120396 0.3048)
			(end -0.120396 0.2794)
			(stroke
				(width 0.1)
				(type default)
			)
			(layer "B.Fab")
		)
		(fp_line
			(start -0.67945 0.3048)
			(end -0.120396 0.3048)
			(stroke
				(width 0.1)
				(type default)
			)
			(layer "B.Fab")
		)
		(pad "1" smd circle
			(at 0.40005 0 270)
			(size 0 0)
			(layers "B.Cu" "B.Mask" "B.Paste")
			(net "P3V3_AUX_USB_HUB_2")
		)
		(pad "2" smd circle
			(at -0.40005 0 270)
			(size 0 0)
			(layers "B.Cu" "B.Mask" "B.Paste")
			(net "GND")
		)
	)
	(footprint ""
		(layer "B.Cu")
		(at 114.734848 -210.194144 180)
		(property "Reference" "C459"
			(at 0 0 0)
			(layer "B.SilkS")
			(hide yes)
			(effects
				(font
					(size 1.27 1.27)
				)
				(justify mirror)
			)
		)
		(property "Value" ""
			(at 0 0 0)
			(layer "B.Fab")
			(effects
				(font
					(size 1.27 1.27)
				)
				(justify mirror)
			)
		)
		(duplicate_pad_numbers_are_jumpers no)
		(fp_line
			(start 1.524 0.762)
			(end 1.524 -0.762)
			(stroke
				(width 0.1524)
				(type default)
			)
			(layer "B.SilkS")
		)
		(fp_line
			(start 1.524 -0.762)
			(end -1.524 -0.762)
			(stroke
				(width 0.1524)
				(type default)
			)
			(layer "B.SilkS")
		)
		(fp_line
			(start -1.524 0.762)
			(end 1.524 0.762)
			(stroke
				(width 0.1524)
				(type default)
			)
			(layer "B.SilkS")
		)
		(fp_line
			(start -1.524 -0.762)
			(end -1.524 0.762)
			(stroke
				(width 0.1524)
				(type default)
			)
			(layer "B.SilkS")
		)
		(fp_line
			(start 1.1049 0.724916)
			(end -1.1049 0.724916)
			(stroke
				(width 0.1)
				(type default)
			)
			(layer "B.Fab")
		)
		(fp_line
			(start 1.1049 -0.724916)
			(end 1.1049 0.724916)
			(stroke
				(width 0.1)
				(type default)
			)
			(layer "B.Fab")
		)
		(fp_line
			(start -1.1049 0.724916)
			(end -1.1049 -0.724916)
			(stroke
				(width 0.1)
				(type default)
			)
			(layer "B.Fab")
		)
		(fp_line
			(start -1.1049 -0.724916)
			(end 1.1049 -0.724916)
			(stroke
				(width 0.1)
				(type default)
			)
			(layer "B.Fab")
		)
		(pad "1" smd rect
			(at 0.889 0 180)
			(size 1.016 1.27)
			(layers "B.Cu" "B.Mask" "B.Paste")
			(net "PVCCD_HV_CPU1")
		)
		(pad "2" smd rect
			(at -0.889 0 180)
			(size 1.016 1.27)
			(layers "B.Cu" "B.Mask" "B.Paste")
			(net "GND")
		)
	)
	(footprint ""
		(layer "B.Cu")
		(at 419.605968 -353.25939 -90)
		(property "Reference" "PC617_P0_1"
			(at 0 0 90)
			(layer "B.SilkS")
			(hide yes)
			(effects
				(font
					(size 1.27 1.27)
				)
				(justify mirror)
			)
		)
		(property "Value" ""
			(at 0 0 90)
			(layer "B.Fab")
			(effects
				(font
					(size 1.27 1.27)
				)
				(justify mirror)
			)
		)
		(duplicate_pad_numbers_are_jumpers no)
		(fp_line
			(start -1.524 0.762)
			(end 1.524 0.762)
			(stroke
				(width 0.1524)
				(type default)
			)
			(layer "B.SilkS")
		)
		(fp_line
			(start 1.524 0.762)
			(end 1.524 -0.762)
			(stroke
				(width 0.1524)
				(type default)
			)
			(layer "B.SilkS")
		)
		(fp_line
			(start -1.524 -0.762)
			(end -1.524 0.762)
			(stroke
				(width 0.1524)
				(type default)
			)
			(layer "B.SilkS")
		)
		(fp_line
			(start 1.524 -0.762)
			(end -1.524 -0.762)
			(stroke
				(width 0.1524)
				(type default)
			)
			(layer "B.SilkS")
		)
		(fp_line
			(start -1.1049 0.724916)
			(end -1.1049 -0.724916)
			(stroke
				(width 0.1)
				(type default)
			)
			(layer "B.Fab")
		)
		(fp_line
			(start 1.1049 0.724916)
			(end -1.1049 0.724916)
			(stroke
				(width 0.1)
				(type default)
			)
			(layer "B.Fab")
		)
		(fp_line
			(start -1.1049 -0.724916)
			(end 1.1049 -0.724916)
			(stroke
				(width 0.1)
				(type default)
			)
			(layer "B.Fab")
		)
		(fp_line
			(start 1.1049 -0.724916)
			(end 1.1049 0.724916)
			(stroke
				(width 0.1)
				(type default)
			)
			(layer "B.Fab")
		)
		(pad "1" smd rect
			(at 0.889 0 270)
			(size 1.016 1.27)
			(layers "B.Cu" "B.Mask" "B.Paste")
			(net "PVCCFA_EHV_FIVRA_CPU0")
		)
		(pad "2" smd rect
			(at -0.889 0 270)
			(size 1.016 1.27)
			(layers "B.Cu" "B.Mask" "B.Paste")
			(net "GND")
		)
	)
)
